# S9S_MB_2U (Grand Teton) — schematic netlist excerpt (pin names and nets, part order shuffled) for the footprints in the layout excerpt that follows; sources: Cadence DE-HDL packaged netlist, KiCad conversion of 03242023_DA0F0TMBIJ0_F0T_Motherboard_J_brd_V01_OCP.brd

R1571  Q_RES  100K 1% CHIP  pkg 0402LF  page 259 : A = MB0_P12V_STBY_PWRGD ; B = P3V3_AUX_EN
R2362  Q_RES  33.2 1% CHIP  pkg 0402LF  page 14 : A = H_CPU0_PMDOWN_CPU1_R ; B = H_CPU0_PMDOWN_CPU1_R1

(kicad_pcb
	(version 20260206)
	(generator "pcbnew")
	(generator_version "10.0")
	(general
		(thickness 1.6)
		(legacy_teardrops no)
	)
	(paper "A4")
	(title_block
		(title "03242023_DA0F0TMBIJ0_F0T_Motherboard_J_brd_V01_OCP.brd")
		(comment 1 "Grand Teton / footprints 5978-5979 of 6105")
	)
	(layers
		(0 "F.Cu" signal "TOP")
		(4 "In1.Cu" signal "GND")
		(6 "In2.Cu" signal "IN1")
		(8 "In3.Cu" signal "GND1")
		(10 "In4.Cu" signal "IN2")
		(12 "In5.Cu" signal "GND2")
		(14 "In6.Cu" signal "IN3")
		(16 "In7.Cu" signal "GND3")
		(18 "In8.Cu" signal "VCC")
		(20 "In9.Cu" signal "VCC1")
		(22 "In10.Cu" signal "GND4")
		(24 "In11.Cu" signal "IN4")
		(26 "In12.Cu" signal "GND5")
		(28 "In13.Cu" signal "IN5")
		(30 "In14.Cu" signal "GND6")
		(32 "In15.Cu" signal "IN6")
		(34 "In16.Cu" signal "GND7")
		(2 "B.Cu" signal "BOTTOM")
		(9 "F.Adhes" user "F.Adhesive")
		(11 "B.Adhes" user "B.Adhesive")
		(13 "F.Paste" user "Package Geometry/Pastemask Top")
		(15 "B.Paste" user "Package Geometry/Pastemask Bottom")
		(5 "F.SilkS" user "Ref Des/Silkscreen Top")
		(7 "B.SilkS" user "Ref Des/Silkscreen Bottom")
		(1 "F.Mask" user "Board Geometry/Soldermask Top")
		(3 "B.Mask" user "Board Geometry/Soldermask Bottom")
		(17 "Dwgs.User" user "User.Drawings")
		(19 "Cmts.User" user "User.Comments")
		(21 "Eco1.User" user "User.Eco1")
		(23 "Eco2.User" user "User.Eco2")
		(25 "Edge.Cuts" user "Board Geometry/Outline")
		(27 "Margin" user)
		(31 "F.CrtYd" user "Package Geometry/Place Bound Top")
		(29 "B.CrtYd" user "Package Geometry/Place Bound Bottom")
		(35 "F.Fab" user "Ref Des/Assembly Top")
		(33 "B.Fab" user "Ref Des/Assembly Bottom")
	)
	(footprint ""
		(layer "B.Cu")
		(at 401.832318 -227.224082 90)
		(property "Reference" "R2362"
			(at 0 0 90)
			(layer "B.SilkS")
			(hide yes)
			(effects
				(font
					(size 1.27 1.27)
				)
				(justify mirror)
			)
		)
		(property "Value" ""
			(at 0 0 90)
			(layer "B.Fab")
			(effects
				(font
					(size 1.27 1.27)
				)
				(justify mirror)
			)
		)
		(duplicate_pad_numbers_are_jumpers no)
		(fp_line
			(start 0.7874 -0.4064)
			(end -0.7874 -0.4064)
			(stroke
				(width 0.1524)
				(type default)
			)
			(layer "B.SilkS")
		)
		(fp_line
			(start -0.7874 -0.4064)
			(end -0.7874 0.4064)
			(stroke
				(width 0.1524)
				(type default)
			)
			(layer "B.SilkS")
		)
		(fp_line
			(start 0.7874 0.4064)
			(end 0.7874 -0.4064)
			(stroke
				(width 0.1524)
				(type default)
			)
			(layer "B.SilkS")
		)
		(fp_line
			(start -0.7874 0.4064)
			(end 0.7874 0.4064)
			(stroke
				(width 0.1524)
				(type default)
			)
			(layer "B.SilkS")
		)
		(fp_line
			(start 0.67945 -0.305054)
			(end 0.12065 -0.305054)
			(stroke
				(width 0.1)
				(type default)
			)
			(layer "B.Fab")
		)
		(fp_line
			(start 0.12065 -0.305054)
			(end 0.12065 -0.2794)
			(stroke
				(width 0.1)
				(type default)
			)
			(layer "B.Fab")
		)
		(fp_line
			(start -0.12065 -0.3048)
			(end -0.67945 -0.3048)
			(stroke
				(width 0.1)
				(type default)
			)
			(layer "B.Fab")
		)
		(fp_line
			(start -0.67945 -0.3048)
			(end -0.67945 0.3048)
			(stroke
				(width 0.1)
				(type default)
			)
			(layer "B.Fab")
		)
		(fp_line
			(start 0.12065 -0.2794)
			(end -0.12065 -0.2794)
			(stroke
				(width 0.1)
				(type default)
			)
			(layer "B.Fab")
		)
		(fp_line
			(start -0.12065 -0.2794)
			(end -0.12065 -0.3048)
			(stroke
				(width 0.1)
				(type default)
			)
			(layer "B.Fab")
		)
		(fp_line
			(start 0.12065 0.2794)
			(end 0.12065 0.3048)
			(stroke
				(width 0.1)
				(type default)
			)
			(layer "B.Fab")
		)
		(fp_line
			(start -0.120396 0.2794)
			(end 0.12065 0.2794)
			(stroke
				(width 0.1)
				(type default)
			)
			(layer "B.Fab")
		)
		(fp_line
			(start 0.67945 0.3048)
			(end 0.67945 -0.305054)
			(stroke
				(width 0.1)
				(type default)
			)
			(layer "B.Fab")
		)
		(fp_line
			(start 0.12065 0.3048)
			(end 0.67945 0.3048)
			(stroke
				(width 0.1)
				(type default)
			)
			(layer "B.Fab")
		)
		(fp_line
			(start -0.120396 0.3048)
			(end -0.120396 0.2794)
			(stroke
				(width 0.1)
				(type default)
			)
			(layer "B.Fab")
		)
		(fp_line
			(start -0.67945 0.3048)
			(end -0.120396 0.3048)
			(stroke
				(width 0.1)
				(type default)
			)
			(layer "B.Fab")
		)
		(pad "1" smd circle
			(at 0.40005 0 270)
			(size 0 0)
			(layers "B.Cu" "B.Mask" "B.Paste")
			(net "H_CPU0_PMDOWN_CPU1_R")
		)
		(pad "2" smd circle
			(at -0.40005 0 270)
			(size 0 0)
			(layers "B.Cu" "B.Mask" "B.Paste")
			(net "H_CPU0_PMDOWN_CPU1_R1")
		)
	)
	(footprint ""
		(layer "B.Cu")
		(at 451.947026 -77.51572 90)
		(property "Reference" "R1571"
			(at 0 0 90)
			(layer "B.SilkS")
			(hide yes)
			(effects
				(font
					(size 1.27 1.27)
				)
				(justify mirror)
			)
		)
		(property "Value" ""
			(at 0 0 90)
			(layer "B.Fab")
			(effects
				(font
					(size 1.27 1.27)
				)
				(justify mirror)
			)
		)
		(duplicate_pad_numbers_are_jumpers no)
		(fp_line
			(start 0.7874 -0.4064)
			(end -0.7874 -0.4064)
			(stroke
				(width 0.1524)
				(type default)
			)
			(layer "B.SilkS")
		)
		(fp_line
			(start -0.7874 -0.4064)
			(end -0.7874 0.4064)
			(stroke
				(width 0.1524)
				(type default)
			)
			(layer "B.SilkS")
		)
		(fp_line
			(start 0.7874 0.4064)
			(end 0.7874 -0.4064)
			(stroke
				(width 0.1524)
				(type default)
			)
			(layer "B.SilkS")
		)
		(fp_line
			(start -0.7874 0.4064)
			(end 0.7874 0.4064)
			(stroke
				(width 0.1524)
				(type default)
			)
			(layer "B.SilkS")
		)
		(fp_line
			(start 0.67945 -0.305054)
			(end 0.12065 -0.305054)
			(stroke
				(width 0.1)
				(type default)
			)
			(layer "B.Fab")
		)
		(fp_line
			(start 0.12065 -0.305054)
			(end 0.12065 -0.2794)
			(stroke
				(width 0.1)
				(type default)
			)
			(layer "B.Fab")
		)
		(fp_line
			(start -0.12065 -0.3048)
			(end -0.67945 -0.3048)
			(stroke
				(width 0.1)
				(type default)
			)
			(layer "B.Fab")
		)
		(fp_line
			(start -0.67945 -0.3048)
			(end -0.67945 0.3048)
			(stroke
				(width 0.1)
				(type default)
			)
			(layer "B.Fab")
		)
		(fp_line
			(start 0.12065 -0.2794)
			(end -0.12065 -0.2794)
			(stroke
				(width 0.1)
				(type default)
			)
			(layer "B.Fab")
		)
		(fp_line
			(start -0.12065 -0.2794)
			(end -0.12065 -0.3048)
			(stroke
				(width 0.1)
				(type default)
			)
			(layer "B.Fab")
		)
		(fp_line
			(start 0.12065 0.2794)
			(end 0.12065 0.3048)
			(stroke
				(width 0.1)
				(type default)
			)
			(layer "B.Fab")
		)
		(fp_line
			(start -0.120396 0.2794)
			(end 0.12065 0.2794)
			(stroke
				(width 0.1)
				(type default)
			)
			(layer "B.Fab")
		)
		(fp_line
			(start 0.67945 0.3048)
			(end 0.67945 -0.305054)
			(stroke
				(width 0.1)
				(type default)
			)
			(layer "B.Fab")
		)
		(fp_line
			(start 0.12065 0.3048)
			(end 0.67945 0.3048)
			(stroke
				(width 0.1)
				(type default)
			)
			(layer "B.Fab")
		)
		(fp_line
			(start -0.120396 0.3048)
			(end -0.120396 0.2794)
			(stroke
				(width 0.1)
				(type default)
			)
			(layer "B.Fab")
		)
		(fp_line
			(start -0.67945 0.3048)
			(end -0.120396 0.3048)
			(stroke
				(width 0.1)
				(type default)
			)
			(layer "B.Fab")
		)
		(pad "1" smd circle
			(at 0.40005 0 270)
			(size 0 0)
			(layers "B.Cu" "B.Mask" "B.Paste")
			(net "MB0_P12V_STBY_PWRGD")
		)
		(pad "2" smd circle
			(at -0.40005 0 270)
			(size 0 0)
			(layers "B.Cu" "B.Mask" "B.Paste")
			(net "P3V3_AUX_EN")
		)
	)
)
